(kicad_pcb
	(version 20260206)
	(generator "pcbnew")
	(generator_version "10.0")
	(general
		(thickness 1.6)
		(legacy_teardrops no)
	)
	(paper "A4")
	(title_block
		(title "panther-plus-userver — 13130-1b_20150205.brd")
		(comment 1 "Honey Badger (Wiwynn) / footprints 174-180 of 1509")
	)
	(layers
		(0 "F.Cu" signal "TOP")
		(4 "In1.Cu" signal "L2")
		(6 "In2.Cu" signal "L3")
		(8 "In3.Cu" signal "L4")
		(10 "In4.Cu" signal "L5")
		(12 "In5.Cu" signal "L6")
		(14 "In6.Cu" signal "L7")
		(16 "In7.Cu" signal "L8")
		(18 "In8.Cu" signal "L9")
		(20 "In9.Cu" signal "L10")
		(22 "In10.Cu" signal "L11")
		(2 "B.Cu" signal "BOTTOM")
		(9 "F.Adhes" user "F.Adhesive")
		(11 "B.Adhes" user "B.Adhesive")
		(13 "F.Paste" user "Package Geometry/Pastemask Top")
		(15 "B.Paste" user "Package Geometry/Pastemask Bottom")
		(5 "F.SilkS" user "Ref Des/Silkscreen Top")
		(7 "B.SilkS" user "Ref Des/Silkscreen Bottom")
		(1 "F.Mask" user "Board Geometry/Soldermask Top")
		(3 "B.Mask" user "Board Geometry/Soldermask Bottom")
		(17 "Dwgs.User" user "User.Drawings")
		(19 "Cmts.User" user "User.Comments")
		(21 "Eco1.User" user "User.Eco1")
		(23 "Eco2.User" user "User.Eco2")
		(25 "Edge.Cuts" user "Board Geometry/Outline")
		(27 "Margin" user)
		(31 "F.CrtYd" user "Package Geometry/Place Bound Top")
		(29 "B.CrtYd" user "Package Geometry/Place Bound Bottom")
		(35 "F.Fab" user "Ref Des/Assembly Top")
		(33 "B.Fab" user "Ref Des/Assembly Bottom")
	)
	(footprint ""
		(layer "F.Cu")
		(at 45.8724 -32.4358 -90)
		(property "Reference" "C115"
			(at 0 0 270)
			(layer "F.SilkS")
			(hide yes)
			(effects
				(font
					(size 1.27 1.27)
				)
			)
		)
		(property "Value" "SCD1U16V2KX-3GP"
			(at 1.1811 -2.7051 270)
			(unlocked yes)
			(layer "F.Fab")
			(hide yes)
			(effects
				(font
					(size 1.016 1.016)
					(thickness 0.1524)
				)
			)
		)
		(property "Device Type" "C402H22"
			(at 1.1811 -4.2291 270)
			(unlocked yes)
			(layer "F.Fab")
			(hide yes)
			(effects
				(font
					(size 1.016 1.016)
					(thickness 0.1524)
				)
			)
		)
		(duplicate_pad_numbers_are_jumpers no)
		(fp_rect
			(start -0.381 0.7366)
			(end 0.381 -0.7366)
			(stroke
				(width 0)
				(type default)
			)
			(fill no)
			(layer "F.CrtYd")
		)
		(fp_rect
			(start -0.381 0.7366)
			(end 0.381 -0.7366)
			(stroke
				(width 0)
				(type default)
			)
			(fill no)
			(layer "F.Fab")
		)
		(pad "1" smd custom
			(at 0 -0.4572 270)
			(size 0.1143 0.1143)
			(layers "F.Cu" "F.Mask" "F.Paste")
			(net "XDP_PWRBTN#")
			(options
				(clearance outline)
				(anchor circle)
			)
			(primitives
				(gr_poly
					(pts
						(arc
							(start -0.254 -0.1778)
							(mid -0.239121 -0.213721)
							(end -0.2032 -0.2286)
						)
						(arc
							(start 0.2032 -0.2286)
							(mid 0.239121 -0.213721)
							(end 0.254 -0.1778)
						)
						(arc
							(start 0.254 0.1778)
							(mid 0.239121 0.213721)
							(end 0.2032 0.2286)
						)
						(arc
							(start -0.2032 0.2286)
							(mid -0.239121 0.213721)
							(end -0.254 0.1778)
						)
					)
					(width 0)
					(fill yes)
				)
			)
		)
		(pad "2" smd custom
			(at 0 0.4572 270)
			(size 0.1143 0.1143)
			(layers "F.Cu" "F.Mask" "F.Paste")
			(net "GND")
			(options
				(clearance outline)
				(anchor circle)
			)
			(primitives
				(gr_poly
					(pts
						(arc
							(start -0.254 -0.1778)
							(mid -0.239121 -0.213721)
							(end -0.2032 -0.2286)
						)
						(arc
							(start 0.2032 -0.2286)
							(mid 0.239121 -0.213721)
							(end 0.254 -0.1778)
						)
						(arc
							(start 0.254 0.1778)
							(mid 0.239121 0.213721)
							(end 0.2032 0.2286)
						)
						(arc
							(start -0.2032 0.2286)
							(mid -0.239121 0.213721)
							(end -0.254 0.1778)
						)
					)
					(width 0)
					(fill yes)
				)
			)
		)
	)
	(footprint ""
		(layer "F.Cu")
		(at 163.449 -45.847)
		(property "Reference" "R216"
			(at 0 0 0)
			(layer "F.SilkS")
			(hide yes)
			(effects
				(font
					(size 1.27 1.27)
				)
			)
		)
		(property "Value" "0R2J-2-GP"
			(at 1.7907 -1.1176 0)
			(unlocked yes)
			(layer "F.Fab")
			(hide yes)
			(effects
				(font
					(size 1.016 1.016)
					(thickness 0.1524)
				)
			)
		)
		(property "Device Type" "R402H16"
			(at 1.7907 -2.6416 0)
			(unlocked yes)
			(layer "F.Fab")
			(hide yes)
			(effects
				(font
					(size 1.016 1.016)
					(thickness 0.1524)
				)
			)
		)
		(duplicate_pad_numbers_are_jumpers no)
		(fp_rect
			(start -0.381 0.8382)
			(end 0.381 -0.8382)
			(stroke
				(width 0)
				(type default)
			)
			(fill no)
			(layer "F.CrtYd")
		)
		(fp_rect
			(start -0.381 0.8382)
			(end 0.381 -0.8382)
			(stroke
				(width 0)
				(type default)
			)
			(fill no)
			(layer "F.Fab")
		)
		(pad "1" smd custom
			(at 0 -0.4318)
			(size 0.127 0.127)
			(layers "F.Cu" "F.Mask" "F.Paste")
			(net "XDP_SOC_CPU_TCK")
			(options
				(clearance outline)
				(anchor circle)
			)
			(primitives
				(gr_poly
					(pts
						(arc
							(start -0.2032 -0.2794)
							(mid -0.239121 -0.264521)
							(end -0.254 -0.2286)
						)
						(arc
							(start -0.254 0.2286)
							(mid -0.239121 0.264521)
							(end -0.2032 0.2794)
						)
						(arc
							(start 0.2032 0.2794)
							(mid 0.239121 0.264521)
							(end 0.254 0.2286)
						)
						(arc
							(start 0.254 -0.2286)
							(mid 0.239121 -0.264521)
							(end 0.2032 -0.2794)
						)
					)
					(width 0)
					(fill yes)
				)
			)
		)
		(pad "2" smd custom
			(at 0 0.4318)
			(size 0.127 0.127)
			(layers "F.Cu" "F.Mask" "F.Paste")
			(net "XDP_SOC_CPU_TCK_S")
			(options
				(clearance outline)
				(anchor circle)
			)
			(primitives
				(gr_poly
					(pts
						(arc
							(start -0.2032 -0.2794)
							(mid -0.239121 -0.264521)
							(end -0.254 -0.2286)
						)
						(arc
							(start -0.254 0.2286)
							(mid -0.239121 0.264521)
							(end -0.2032 0.2794)
						)
						(arc
							(start 0.2032 0.2794)
							(mid 0.239121 0.264521)
							(end 0.254 0.2286)
						)
						(arc
							(start 0.254 -0.2286)
							(mid 0.239121 -0.264521)
							(end 0.2032 -0.2794)
						)
					)
					(width 0)
					(fill yes)
				)
			)
		)
	)
	(footprint ""
		(layer "F.Cu")
		(at 16.0528 -50.3682 90)
		(property "Reference" "PC148"
			(at 0 0 90)
			(layer "F.SilkS")
			(hide yes)
			(effects
				(font
					(size 1.27 1.27)
				)
			)
		)
		(property "Value" "SC4700P50V2KX-1GP"
			(at 1.8923 -1.2065 90)
			(unlocked yes)
			(layer "F.Fab")
			(hide yes)
			(effects
				(font
					(size 1.016 1.016)
					(thickness 0.1524)
				)
			)
		)
		(property "Device Type" "C402H22"
			(at 1.8923 -2.7305 90)
			(unlocked yes)
			(layer "F.Fab")
			(hide yes)
			(effects
				(font
					(size 1.016 1.016)
					(thickness 0.1524)
				)
			)
		)
		(duplicate_pad_numbers_are_jumpers no)
		(fp_rect
			(start -0.381 0.7366)
			(end 0.381 -0.7366)
			(stroke
				(width 0)
				(type default)
			)
			(fill no)
			(layer "F.CrtYd")
		)
		(fp_rect
			(start -0.381 0.7366)
			(end 0.381 -0.7366)
			(stroke
				(width 0)
				(type default)
			)
			(fill no)
			(layer "F.Fab")
		)
		(pad "1" smd custom
			(at 0 -0.4572 90)
			(size 0.1143 0.1143)
			(layers "F.Cu" "F.Mask" "F.Paste")
			(net "VR_PVCCP_COMP")
			(options
				(clearance outline)
				(anchor circle)
			)
			(primitives
				(gr_poly
					(pts
						(arc
							(start -0.254 -0.1778)
							(mid -0.239121 -0.213721)
							(end -0.2032 -0.2286)
						)
						(arc
							(start 0.2032 -0.2286)
							(mid 0.239121 -0.213721)
							(end 0.254 -0.1778)
						)
						(arc
							(start 0.254 0.1778)
							(mid 0.239121 0.213721)
							(end 0.2032 0.2286)
						)
						(arc
							(start -0.2032 0.2286)
							(mid -0.239121 0.213721)
							(end -0.254 0.1778)
						)
					)
					(width 0)
					(fill yes)
				)
			)
		)
		(pad "2" smd custom
			(at 0 0.4572 90)
			(size 0.1143 0.1143)
			(layers "F.Cu" "F.Mask" "F.Paste")
			(net "VR_PVCCP_COMP_RC")
			(options
				(clearance outline)
				(anchor circle)
			)
			(primitives
				(gr_poly
					(pts
						(arc
							(start -0.254 -0.1778)
							(mid -0.239121 -0.213721)
							(end -0.2032 -0.2286)
						)
						(arc
							(start 0.2032 -0.2286)
							(mid 0.239121 -0.213721)
							(end 0.254 -0.1778)
						)
						(arc
							(start 0.254 0.1778)
							(mid 0.239121 0.213721)
							(end 0.2032 0.2286)
						)
						(arc
							(start -0.2032 0.2286)
							(mid -0.239121 0.213721)
							(end -0.254 0.1778)
						)
					)
					(width 0)
					(fill yes)
				)
			)
		)
	)
	(footprint ""
		(layer "F.Cu")
		(at 24.511 -43.307 180)
		(property "Reference" "PC150"
			(at 0 0 180)
			(layer "F.SilkS")
			(hide yes)
			(effects
				(font
					(size 1.27 1.27)
				)
			)
		)
		(property "Value" "SCD1U25V2KX-2-GP"
			(at 1.8923 -1.2065 180)
			(unlocked yes)
			(layer "F.Fab")
			(hide yes)
			(effects
				(font
					(size 1.016 1.016)
					(thickness 0.1524)
				)
			)
		)
		(property "Device Type" "C402H22"
			(at 1.8923 -2.7305 180)
			(unlocked yes)
			(layer "F.Fab")
			(hide yes)
			(effects
				(font
					(size 1.016 1.016)
					(thickness 0.1524)
				)
			)
		)
		(duplicate_pad_numbers_are_jumpers no)
		(fp_rect
			(start -0.381 0.7366)
			(end 0.381 -0.7366)
			(stroke
				(width 0)
				(type default)
			)
			(fill no)
			(layer "F.CrtYd")
		)
		(fp_rect
			(start -0.381 0.7366)
			(end 0.381 -0.7366)
			(stroke
				(width 0)
				(type default)
			)
			(fill no)
			(layer "F.Fab")
		)
		(pad "1" smd custom
			(at 0 -0.4572 180)
			(size 0.1143 0.1143)
			(layers "F.Cu" "F.Mask" "F.Paste")
			(net "P3V3_STBY_OUT")
			(options
				(clearance outline)
				(anchor circle)
			)
			(primitives
				(gr_poly
					(pts
						(arc
							(start -0.254 -0.1778)
							(mid -0.239121 -0.213721)
							(end -0.2032 -0.2286)
						)
						(arc
							(start 0.2032 -0.2286)
							(mid 0.239121 -0.213721)
							(end 0.254 -0.1778)
						)
						(arc
							(start 0.254 0.1778)
							(mid 0.239121 0.213721)
							(end 0.2032 0.2286)
						)
						(arc
							(start -0.2032 0.2286)
							(mid -0.239121 0.213721)
							(end -0.254 0.1778)
						)
					)
					(width 0)
					(fill yes)
				)
			)
		)
		(pad "2" smd custom
			(at 0 0.4572 180)
			(size 0.1143 0.1143)
			(layers "F.Cu" "F.Mask" "F.Paste")
			(net "GND")
			(options
				(clearance outline)
				(anchor circle)
			)
			(primitives
				(gr_poly
					(pts
						(arc
							(start -0.254 -0.1778)
							(mid -0.239121 -0.213721)
							(end -0.2032 -0.2286)
						)
						(arc
							(start 0.2032 -0.2286)
							(mid 0.239121 -0.213721)
							(end 0.254 -0.1778)
						)
						(arc
							(start 0.254 0.1778)
							(mid 0.239121 0.213721)
							(end 0.2032 0.2286)
						)
						(arc
							(start -0.2032 0.2286)
							(mid -0.239121 0.213721)
							(end -0.254 0.1778)
						)
					)
					(width 0)
					(fill yes)
				)
			)
		)
	)
	(footprint ""
		(layer "F.Cu")
		(at 71.882 -56.388 90)
		(property "Reference" "R312"
			(at 0 0 90)
			(layer "F.SilkS")
			(hide yes)
			(effects
				(font
					(size 1.27 1.27)
				)
			)
		)
		(property "Value" "4K7R2F-GP"
			(at 0.064008 -3.993896 90)
			(unlocked yes)
			(layer "F.Fab")
			(hide yes)
			(effects
				(font
					(size 1.016 1.016)
					(thickness 0.1524)
				)
			)
		)
		(property "Device Type" "R402H16"
			(at 0.064008 -5.517896 90)
			(unlocked yes)
			(layer "F.Fab")
			(hide yes)
			(effects
				(font
					(size 1.016 1.016)
					(thickness 0.1524)
				)
			)
		)
		(duplicate_pad_numbers_are_jumpers no)
		(fp_rect
			(start -0.381 0.8382)
			(end 0.381 -0.8382)
			(stroke
				(width 0)
				(type default)
			)
			(fill no)
			(layer "F.CrtYd")
		)
		(fp_rect
			(start -0.381 0.8382)
			(end 0.381 -0.8382)
			(stroke
				(width 0)
				(type default)
			)
			(fill no)
			(layer "F.Fab")
		)
		(pad "1" smd custom
			(at 0 -0.4318 90)
			(size 0.127 0.127)
			(layers "F.Cu" "F.Mask" "F.Paste")
			(net "P3V3_STBY")
			(options
				(clearance outline)
				(anchor circle)
			)
			(primitives
				(gr_poly
					(pts
						(arc
							(start -0.2032 -0.2794)
							(mid -0.239121 -0.264521)
							(end -0.254 -0.2286)
						)
						(arc
							(start -0.254 0.2286)
							(mid -0.239121 0.264521)
							(end -0.2032 0.2794)
						)
						(arc
							(start 0.2032 0.2794)
							(mid 0.239121 0.264521)
							(end 0.254 0.2286)
						)
						(arc
							(start 0.254 -0.2286)
							(mid 0.239121 -0.264521)
							(end 0.2032 -0.2794)
						)
					)
					(width 0)
					(fill yes)
				)
			)
		)
		(pad "2" smd custom
			(at 0 0.4318 90)
			(size 0.127 0.127)
			(layers "F.Cu" "F.Mask" "F.Paste")
			(net "BMC_I2C_DATA")
			(options
				(clearance outline)
				(anchor circle)
			)
			(primitives
				(gr_poly
					(pts
						(arc
							(start -0.2032 -0.2794)
							(mid -0.239121 -0.264521)
							(end -0.254 -0.2286)
						)
						(arc
							(start -0.254 0.2286)
							(mid -0.239121 0.264521)
							(end -0.2032 0.2794)
						)
						(arc
							(start 0.2032 0.2794)
							(mid 0.239121 0.264521)
							(end 0.254 0.2286)
						)
						(arc
							(start 0.254 -0.2286)
							(mid 0.239121 -0.264521)
							(end 0.2032 -0.2794)
						)
					)
					(width 0)
					(fill yes)
				)
			)
		)
	)
	(footprint ""
		(layer "F.Cu")
		(at 59.436 -25.146 -90)
		(property "Reference" "R253"
			(at 0 0 270)
			(layer "F.SilkS")
			(hide yes)
			(effects
				(font
					(size 1.27 1.27)
				)
			)
		)
		(property "Value" "1KR2F-3-GP"
			(at 0.064008 -3.993896 270)
			(unlocked yes)
			(layer "F.Fab")
			(hide yes)
			(effects
				(font
					(size 1.016 1.016)
					(thickness 0.1524)
				)
			)
		)
		(property "Device Type" "R402H16"
			(at 0.064008 -5.517896 270)
			(unlocked yes)
			(layer "F.Fab")
			(hide yes)
			(effects
				(font
					(size 1.016 1.016)
					(thickness 0.1524)
				)
			)
		)
		(duplicate_pad_numbers_are_jumpers no)
		(fp_rect
			(start -0.381 0.8382)
			(end 0.381 -0.8382)
			(stroke
				(width 0)
				(type default)
			)
			(fill no)
			(layer "F.CrtYd")
		)
		(fp_rect
			(start -0.381 0.8382)
			(end 0.381 -0.8382)
			(stroke
				(width 0)
				(type default)
			)
			(fill no)
			(layer "F.Fab")
		)
		(pad "1" smd custom
			(at 0 -0.4318 270)
			(size 0.127 0.127)
			(layers "F.Cu" "F.Mask" "F.Paste")
			(net "P3V3_STBY")
			(options
				(clearance outline)
				(anchor circle)
			)
			(primitives
				(gr_poly
					(pts
						(arc
							(start -0.2032 -0.2794)
							(mid -0.239121 -0.264521)
							(end -0.254 -0.2286)
						)
						(arc
							(start -0.254 0.2286)
							(mid -0.239121 0.264521)
							(end -0.2032 0.2794)
						)
						(arc
							(start 0.2032 0.2794)
							(mid 0.239121 0.264521)
							(end 0.254 0.2286)
						)
						(arc
							(start 0.254 -0.2286)
							(mid 0.239121 -0.264521)
							(end 0.2032 -0.2794)
						)
					)
					(width 0)
					(fill yes)
				)
			)
		)
		(pad "2" smd custom
			(at 0 0.4318 270)
			(size 0.127 0.127)
			(layers "F.Cu" "F.Mask" "F.Paste")
			(net "P1V8_G")
			(options
				(clearance outline)
				(anchor circle)
			)
			(primitives
				(gr_poly
					(pts
						(arc
							(start -0.2032 -0.2794)
							(mid -0.239121 -0.264521)
							(end -0.254 -0.2286)
						)
						(arc
							(start -0.254 0.2286)
							(mid -0.239121 0.264521)
							(end -0.2032 0.2794)
						)
						(arc
							(start 0.2032 0.2794)
							(mid 0.239121 0.264521)
							(end 0.254 0.2286)
						)
						(arc
							(start 0.254 -0.2286)
							(mid 0.239121 -0.264521)
							(end 0.2032 -0.2794)
						)
					)
					(width 0)
					(fill yes)
				)
			)
		)
	)
	(footprint ""
		(layer "F.Cu")
		(at 157.48 -47.498 90)
		(property "Reference" "Q6"
			(at 0 0 90)
			(layer "F.SilkS")
			(hide yes)
			(effects
				(font
					(size 1.27 1.27)
				)
			)
		)
		(property "Value" "2N7002A-7-GP"
			(at -4.3561 -5.7912 90)
			(unlocked yes)
			(layer "F.Fab")
			(hide yes)
			(effects
				(font
					(size 1.016 1.016)
					(thickness 0.1524)
				)
			)
		)
		(property "Device Type" "SOT23DGS2D4H48"
			(at -4.3561 -7.3152 90)
			(unlocked yes)
			(layer "F.Fab")
			(hide yes)
			(effects
				(font
					(size 1.016 1.016)
					(thickness 0.1524)
				)
			)
		)
		(duplicate_pad_numbers_are_jumpers no)
		(fp_line
			(start 1.7145 -0.4445)
			(end -1.7145 -0.4445)
			(stroke
				(width 0.1524)
				(type default)
			)
			(layer "F.SilkS")
		)
		(fp_line
			(start -1.7145 -0.4445)
			(end -1.7145 0.4445)
			(stroke
				(width 0.1524)
				(type default)
			)
			(layer "F.SilkS")
		)
		(fp_line
			(start 1.7145 0.4445)
			(end 1.7145 -0.4445)
			(stroke
				(width 0.1524)
				(type default)
			)
			(layer "F.SilkS")
		)
		(fp_line
			(start -1.7145 0.4445)
			(end 1.7145 0.4445)
			(stroke
				(width 0.1524)
				(type default)
			)
			(layer "F.SilkS")
		)
		(fp_poly
			(pts
				(xy -1.4224 1.5621) (xy -1.4224 0.9017) (xy -1.7145 0.9017) (xy -1.7145 -0.9017) (xy -0.4699 -0.9017)
				(xy -0.4699 -1.5621) (xy 0.4699 -1.5621) (xy 0.4699 -0.9017) (xy 1.7145 -0.9017) (xy 1.7145 0.9017)
				(xy 1.4224 0.9017) (xy 1.4224 1.5621) (xy 0.4826 1.5621) (xy 0.4826 0.9017) (xy -0.4826 0.9017)
				(xy -0.4826 1.5621)
			)
			(stroke
				(width 0)
				(type default)
			)
			(fill no)
			(layer "F.CrtYd")
		)
		(fp_poly
			(pts
				(xy -1.4224 1.5621) (xy -1.4224 0.9017) (xy -1.7145 0.9017) (xy -1.7145 -0.9017) (xy -0.4699 -0.9017)
				(xy -0.4699 -1.5621) (xy 0.4699 -1.5621) (xy 0.4699 -0.9017) (xy 1.7145 -0.9017) (xy 1.7145 0.9017)
				(xy 1.4224 0.9017) (xy 1.4224 1.5621) (xy 0.4826 1.5621) (xy 0.4826 0.9017) (xy -0.4826 0.9017)
				(xy -0.4826 1.5621)
			)
			(stroke
				(width 0)
				(type default)
			)
			(fill no)
			(layer "F.Fab")
		)
		(pad "D" smd custom
			(at 0 -1.069086 90)
			(size 0.17145 0.17145)
			(layers "F.Cu" "F.Mask" "F.Paste")
			(net "JTAG_CPU_PLD_TDO_D")
			(options
				(clearance outline)
				(anchor circle)
			)
			(primitives
				(gr_poly
					(pts
						(arc
							(start -0.1397 0.3683)
							(mid -0.283384 0.308784)
							(end -0.3429 0.1651)
						)
						(arc
							(start -0.3429 -0.1651)
							(mid -0.283384 -0.308784)
							(end -0.1397 -0.3683)
						)
						(arc
							(start 0.1397 -0.3683)
							(mid 0.283384 -0.308784)
							(end 0.3429 -0.1651)
						)
						(arc
							(start 0.3429 0.1651)
							(mid 0.283384 0.308784)
							(end 0.1397 0.3683)
						)
					)
					(width 0)
					(fill yes)
				)
			)
		)
		(pad "G" smd custom
			(at -0.94996 1.069086 90)
			(size 0.17145 0.17145)
			(layers "F.Cu" "F.Mask" "F.Paste")
			(net "JTAG_CHAIN_EN")
			(options
				(clearance outline)
				(anchor circle)
			)
			(primitives
				(gr_poly
					(pts
						(arc
							(start -0.1397 0.3683)
							(mid -0.283384 0.308784)
							(end -0.3429 0.1651)
						)
						(arc
							(start -0.3429 -0.1651)
							(mid -0.283384 -0.308784)
							(end -0.1397 -0.3683)
						)
						(arc
							(start 0.1397 -0.3683)
							(mid 0.283384 -0.308784)
							(end 0.3429 -0.1651)
						)
						(arc
							(start 0.3429 0.1651)
							(mid 0.283384 0.308784)
							(end 0.1397 0.3683)
						)
					)
					(width 0)
					(fill yes)
				)
			)
		)
		(pad "S" smd custom
			(at 0.94996 1.069086 90)
			(size 0.17145 0.17145)
			(layers "F.Cu" "F.Mask" "F.Paste")
			(net "XDP_SOC_CPU_TDO_S")
			(options
				(clearance outline)
				(anchor circle)
			)
			(primitives
				(gr_poly
					(pts
						(arc
							(start -0.1397 0.3683)
							(mid -0.283384 0.308784)
							(end -0.3429 0.1651)
						)
						(arc
							(start -0.3429 -0.1651)
							(mid -0.283384 -0.308784)
							(end -0.1397 -0.3683)
						)
						(arc
							(start 0.1397 -0.3683)
							(mid 0.283384 -0.308784)
							(end 0.3429 -0.1651)
						)
						(arc
							(start 0.3429 0.1651)
							(mid 0.283384 0.308784)
							(end 0.1397 0.3683)
						)
					)
					(width 0)
					(fill yes)
				)
			)
		)
	)
)
